# S9S_MB_2U (Grand Teton) — schematic netlist excerpt (pin names and nets, part order shuffled) for the footprints in the layout excerpt that follows; sources: Cadence DE-HDL packaged netlist, KiCad conversion of 03242023_DA0F0TMBIJ0_F0T_Motherboard_J_brd_V01_OCP.brd

J20  SCONN288_ADR50017P087CC  SCONN288_ADR50017-P087CC IO  pkg DDR288S_1-1VXB  page 101
  VIN_BULK0  = P12V_S3_AUX_CPU1_NVDIMM
  RFU0  = TP_CHB_CPU1_DIMM2_FRU_0
  VIN_MGMT  = P3V3_AUX
  HSCL  = I3C_SPD_DDRABCD_CPU1_LVC1_SCL_3
  HSDA  = I3C_SPD_DDRABCD_CPU1_LVC1_SDA
  VSS0  = GND
  DQ0_A  = M_B_CPU1_SA_DQ<0>
  VSS1  = GND
  DQ1_A  = M_B_CPU1_SA_DQ<1>
  VSS2  = GND
  DQS0_A_T  = M_B_CPU1_SA_DQS_DP<0>
  DQS0_A_C  = M_B_CPU1_SA_DQS_DN<0>
  VSS3  = GND
  DQ4_A  = M_B_CPU1_SA_DQ<4>
  VSS4  = GND
  DQ5_A  = M_B_CPU1_SA_DQ<5>
  VSS5  = GND
  DQ8_A  = M_B_CPU1_SA_DQ<8>
  VSS6  = GND
  DQ9_A  = M_B_CPU1_SA_DQ<9>
  VSS7  = GND
  DQS1_A_T  = M_B_CPU1_SA_DQS_DP<1>
  DQS1_A_C  = M_B_CPU1_SA_DQS_DN<1>
  VSS8  = GND
  DQ12_A  = M_B_CPU1_SA_DQ<12>
  VSS9  = GND
  DQ13_A  = M_B_CPU1_SA_DQ<13>
  VSS10  = GND
  DQ16_A  = M_B_CPU1_SA_DQ<16>
  VSS11  = GND
  DQ17_A  = M_B_CPU1_SA_DQ<17>
  VSS12  = GND
  DQS2_A_T  = M_B_CPU1_SA_DQS_DP<2>
  DQS2_A_C  = M_B_CPU1_SA_DQS_DN<2>
  VSS13  = GND
  DQ20_A  = M_B_CPU1_SA_DQ<20>
  VSS14  = GND
  DQ21_A  = M_B_CPU1_SA_DQ<21>
  VSS15  = GND
  DQ24_A  = M_B_CPU1_SA_DQ<24>
  VSS16  = GND
  DQ25_A  = M_B_CPU1_SA_DQ<25>
  VSS17  = GND
  DQS3_A_T  = M_B_CPU1_SA_DQS_DP<3>
  DQS3_A_C  = M_B_CPU1_SA_DQS_DN<3>
  VSS18  = GND
  DQ28_A  = M_B_CPU1_SA_DQ<28>
  VSS19  = GND
  DQ29_A  = M_B_CPU1_SA_DQ<29>
  VSS20  = GND
  CB0_A  = M_B_CPU1_SA_CB<0>
  VSS21  = GND
  CB1_A  = M_B_CPU1_SA_CB<1>
  VSS22  = GND
  DQS4_A_T  = M_B_CPU1_SA_DQS_DP<4>
  DQS4_A_C  = M_B_CPU1_SA_DQS_DN<4>
  VSS23  = GND
  CB4_A  = M_B_CPU1_SA_CB<4>
  VSS24  = GND
  CB5_A  = M_B_CPU1_SA_CB<5>
  VSS25  = GND
  ALERT_N  = M_B_CPU1_ALERT_N
  VSS26  = GND
  CS0_A_N  = M_B_CPU1_SA_CS_N<2>
  VSS27  = GND
  CA0_A  = M_B_CPU1_SA_CA<0>
  VSS28  = GND
  CA2_A  = M_B_CPU1_SA_CA<2>
  VSS29  = GND
  CA4_A  = M_B_CPU1_SA_CA<4>
  VSS30  = GND
  CA6_A  = M_B_CPU1_SA_CA<6>
  VSS31  = GND
  PAR_A  = M_B_CPU1_SA_PAR
  VSS32  = GND
  CA0_B  = M_B_CPU1_SB_CA<0>
  VSS33  = GND
  CA2_B  = M_B_CPU1_SB_CA<2>
  VSS34  = GND
  CA4_B  = M_B_CPU1_SB_CA<4>
  VSS35  = GND
  CA6_B  = M_B_CPU1_SB_CA<6>
  VSS36  = GND
  CS0_B_N  = M_B_CPU1_SB_CS_N<2>
  VSS37  = GND
  \lbd||rsp_a_n\  = M_B_CPU1_SA_RSP<1>
  \lbs||rsp_b_n\  = M_B_CPU1_SB_RSP<1>
  VSS38  = GND
  CB4_B  = M_B_CPU1_SB_CB<4>
  VSS39  = GND
  CB5_B  = M_B_CPU1_SB_CB<5>
  VSS40  = GND
  \dqs9_b_t||tdqs9_b_t||dbi4_b_n\  = M_B_CPU1_SB_DQS_DP<9>
  \dqs9_b_c||tdqs9_b_c\  = M_B_CPU1_SB_DQS_DN<9>
  VSS41  = GND
  CB0_B  = M_B_CPU1_SB_CB<0>
  VSS42  = GND
  CB1_B  = M_B_CPU1_SB_CB<1>
  VSS43  = GND
  DQ0_B  = M_B_CPU1_SB_DQ<0>
  VSS44  = GND
  DQ1_B  = M_B_CPU1_SB_DQ<1>
  VSS45  = GND
  DQS0_B_T  = M_B_CPU1_SB_DQS_DP<0>
  DQS0_B_C  = M_B_CPU1_SB_DQS_DN<0>
  VSS46  = GND
  DQ4_B  = M_B_CPU1_SB_DQ<4>
  VSS47  = GND
  DQ5_B  = M_B_CPU1_SB_DQ<5>
  VSS48  = GND
  DQ8_B  = M_B_CPU1_SB_DQ<8>
  VSS49  = GND
  DQ9_B  = M_B_CPU1_SB_DQ<9>
  VSS50  = GND
  DQS1_B_T  = M_B_CPU1_SB_DQS_DP<1>
  DQS1_B_C  = M_B_CPU1_SB_DQS_DN<1>
  VSS51  = GND
  DQ12_B  = M_B_CPU1_SB_DQ<12>
  VSS52  = GND
  DQ13_B  = M_B_CPU1_SB_DQ<13>
  VSS53  = GND
  DQ16_B  = M_B_CPU1_SB_DQ<16>
  VSS54  = GND
  DQ17_B  = M_B_CPU1_SB_DQ<17>
  VSS55  = GND
  DQS2_B_T  = M_B_CPU1_SB_DQS_DP<2>
  DQS2_B_C  = M_B_CPU1_SB_DQS_DN<2>
  VSS56  = GND
  DQ20_B  = M_B_CPU1_SB_DQ<20>
  VSS57  = GND
  DQ21_B  = M_B_CPU1_SB_DQ<21>
  VSS58  = GND
  DQ24_B  = M_B_CPU1_SB_DQ<24>
  VSS59  = GND
  DQ25_B  = M_B_CPU1_SB_DQ<25>
  VSS60  = GND
  DQS3_B_T  = M_B_CPU1_SB_DQS_DP<3>
  DQS3_B_C  = M_B_CPU1_SB_DQS_DN<3>
  VSS61  = GND
  DQ28_B  = M_B_CPU1_SB_DQ<28>
  VSS62  = GND
  DQ29_B  = M_B_CPU1_SB_DQ<29>
  VSS63  = GND
  RFU1  = TP_CHB_CPU1_DIMM2_FRU_1
  VIN_BULK1  = P12V_S3_AUX_CPU1_NVDIMM
  VIN_BULK2  = P12V_S3_AUX_CPU1_NVDIMM
  \pwr_good||fail_n\  = PWRGD_CHB_CPU1_DIMM2
  HSA  = PD_CHB_CPU1_DIMM2_SAA
  RFU2  = TP_CHB_CPU1_DIMM2_FRU_2
  RFU3  = TP_CHB_CPU1_DIMM2_FRU_3
  VSS64  = GND
  DQ2_A  = M_B_CPU1_SA_DQ<2>
  VSS65  = GND
  DQ3_A  = M_B_CPU1_SA_DQ<3>
  VSS66  = GND
  \dqs5_a_c||tdqs5_a_c||dqs5_a_t||tdqs5_a_t\  = M_B_CPU1_SA_DQS_DN<5>
  \dqs5_a_t||tdqs5_a_t\  = M_B_CPU1_SA_DQS_DP<5>
  VSS67  = GND
  DQ6_A  = M_B_CPU1_SA_DQ<6>
  VSS68  = GND
  DQ7_A  = M_B_CPU1_SA_DQ<7>
  VSS69  = GND
  DQ10_A  = M_B_CPU1_SA_DQ<10>
  VSS70  = GND
  DQ11_A  = M_B_CPU1_SA_DQ<11>
  VSS71  = GND
  \dqs6_a_c||tdqs6_a_c||dqs6_a_t||tdqs6_a_t\  = M_B_CPU1_SA_DQS_DN<6>
  \dqs6_a_t||tdqs6_a_t\  = M_B_CPU1_SA_DQS_DP<6>
  VSS72  = GND
  DQ14_A  = M_B_CPU1_SA_DQ<14>
  VSS73  = GND
  DQ15_A  = M_B_CPU1_SA_DQ<15>
  VSS74  = GND
  DQ18_A  = M_B_CPU1_SA_DQ<18>
  VSS75  = GND
  DQ19_A  = M_B_CPU1_SA_DQ<19>
  VSS76  = GND
  \dqs7_a_c||tdqs7_a_c\  = M_B_CPU1_SA_DQS_DN<7>
  \dqs7_a_t||tdqs7_a_t\  = M_B_CPU1_SA_DQS_DP<7>
  VSS77  = GND
  DQ22_A  = M_B_CPU1_SA_DQ<22>
  VSS78  = GND
  DQ23_A  = M_B_CPU1_SA_DQ<23>
  VSS79  = GND
  DQ26_A  = M_B_CPU1_SA_DQ<26>
  VSS80  = GND
  DQ27_A  = M_B_CPU1_SA_DQ<27>
  VSS81  = GND
  \dqs8_a_c||tdqs8_a_c\  = M_B_CPU1_SA_DQS_DN<8>
  \dqs8_a_t||tdqs8_a_t\  = M_B_CPU1_SA_DQS_DP<8>
  VSS82  = GND
  DQ30_A  = M_B_CPU1_SA_DQ<30>
  VSS83  = GND
  DQ31_A  = M_B_CPU1_SA_DQ<31>
  VSS84  = GND
  CB2_A  = M_B_CPU1_SA_CB<2>
  VSS85  = GND
  CB3_A  = M_B_CPU1_SA_CB<3>
  VSS86  = GND
  \dqs9_a_c||tdqs9_a_c\  = M_B_CPU1_SA_DQS_DN<9>
  \dqs9_a_t||tdqs9_a_t\  = M_B_CPU1_SA_DQS_DP<9>
  VSS87  = GND
  CB6_A  = M_B_CPU1_SA_CB<6>
  VSS88  = GND
  CB7_A  = M_B_CPU1_SA_CB<7>
  VSS89  = GND
  RESET_N  = RST_M_AB_CPU1_FPGA_N
  VSS90  = GND
  CS1_A_N  = M_B_CPU1_SA_CS_N<3>
  VSS91  = GND
  CA1_A  = M_B_CPU1_SA_CA<1>
  VSS92  = GND
  CA3_A  = M_B_CPU1_SA_CA<3>
  VSS93  = GND
  CA5_A  = M_B_CPU1_SA_CA<5>
  VSS94  = GND
  CK_T  = M_B_CPU1_CLK_DP<1>
  CK_C  = M_B_CPU1_CLK_DN<1>
  VSS95  = GND
  RFU4  = TP_CHB_CPU1_DIMM2_FRU_4
  CA1_B  = M_B_CPU1_SB_CA<1>
  VSS96  = GND
  CA3_B  = M_B_CPU1_SB_CA<3>
  VSS97  = GND
  CA5_B  = M_B_CPU1_SB_CA<5>
  VSS98  = GND
  PAR_B  = M_B_CPU1_SB_PAR
  VSS99  = GND
  CS1_B_N  = M_B_CPU1_SB_CS_N<3>
  VSS100  = GND
  RFU5  = TP_CHB_CPU1_DIMM2_FRU_5
  RFU6  = TP_CHB_CPU1_DIMM2_FRU_6
  VSS101  = GND
  CB6_B  = M_B_CPU1_SB_CB<6>
  VSS102  = GND
  CB7_B  = M_B_CPU1_SB_CB<7>
  VSS103  = GND
  DQS4_B_C  = M_B_CPU1_SB_DQS_DN<4>
  DQS4_B_T  = M_B_CPU1_SB_DQS_DP<4>
  VSS104  = GND
  CB2_B  = M_B_CPU1_SB_CB<2>
  VSS105  = GND
  CB3_B  = M_B_CPU1_SB_CB<3>
  VSS106  = GND
  DQ2_B  = M_B_CPU1_SB_DQ<2>
  VSS107  = GND
  DQ3_B  = M_B_CPU1_SB_DQ<3>
  VSS108  = GND
  \dqs5_b_c||tdqs5_b_c\  = M_B_CPU1_SB_DQS_DN<5>
  \dqs5_b_t||tdqs5_b_t\  = M_B_CPU1_SB_DQS_DP<5>
  VSS109  = GND
  DQ6_B  = M_B_CPU1_SB_DQ<6>
  VSS110  = GND
  DQ7_B  = M_B_CPU1_SB_DQ<7>
  VSS111  = GND
  DQ10_B  = M_B_CPU1_SB_DQ<10>
  VSS112  = GND
  DQ11_B  = M_B_CPU1_SB_DQ<11>
  VSS113  = GND
  \dqs6_b_c||tdqs6_b_c\  = M_B_CPU1_SB_DQS_DN<6>
  \dqs6_b_t||tdqs6_b_t\  = M_B_CPU1_SB_DQS_DP<6>
  VSS114  = GND
  DQ14_B  = M_B_CPU1_SB_DQ<14>
  VSS115  = GND
  DQ15_B  = M_B_CPU1_SB_DQ<15>
  VSS116  = GND
  DQ18_B  = M_B_CPU1_SB_DQ<18>
  VSS117  = GND
  DQ19_B  = M_B_CPU1_SB_DQ<19>
  VSS118  = GND
  \dqs7_b_c||tdqs7_b_c\  = M_B_CPU1_SB_DQS_DN<7>
  \dqs7_b_t||tdqs7_b_t\  = M_B_CPU1_SB_DQS_DP<7>
  VSS119  = GND
  DQ22_B  = M_B_CPU1_SB_DQ<22>
  VSS120  = GND
  DQ23_B  = M_B_CPU1_SB_DQ<23>
  VSS121  = GND
  DQ26_B  = M_B_CPU1_SB_DQ<26>
  VSS122  = GND
  DQ27_B  = M_B_CPU1_SB_DQ<27>
  VSS123  = GND
  \dqs8_b_c||tdqs8_b_c\  = M_B_CPU1_SB_DQS_DN<8>
  \dqs8_b_t||tdqs8_b_t\  = M_B_CPU1_SB_DQS_DP<8>
  VSS124  = GND
  DQ30_B  = M_B_CPU1_SB_DQ<30>
  VSS125  = GND
  DQ31_B  = M_B_CPU1_SB_DQ<31>
  VSS126  = GND
  G1  = GND
  G2  = GND
  G3  = GND

(kicad_pcb
	(version 20260206)
	(generator "pcbnew")
	(generator_version "10.0")
	(general
		(thickness 1.6)
		(legacy_teardrops no)
	)
	(paper "A4")
	(title_block
		(title "03242023_DA0F0TMBIJ0_F0T_Motherboard_J_brd_V01_OCP.brd")
		(comment 1 "Grand Teton / footprint 1508 of 6105 (J20), pads 275-291 of 291")
	)
	(layers
		(0 "F.Cu" signal "TOP")
		(4 "In1.Cu" signal "GND")
		(6 "In2.Cu" signal "IN1")
		(8 "In3.Cu" signal "GND1")
		(10 "In4.Cu" signal "IN2")
		(12 "In5.Cu" signal "GND2")
		(14 "In6.Cu" signal "IN3")
		(16 "In7.Cu" signal "GND3")
		(18 "In8.Cu" signal "VCC")
		(20 "In9.Cu" signal "VCC1")
		(22 "In10.Cu" signal "GND4")
		(24 "In11.Cu" signal "IN4")
		(26 "In12.Cu" signal "GND5")
		(28 "In13.Cu" signal "IN5")
		(30 "In14.Cu" signal "GND6")
		(32 "In15.Cu" signal "IN6")
		(34 "In16.Cu" signal "GND7")
		(2 "B.Cu" signal "BOTTOM")
		(9 "F.Adhes" user "F.Adhesive")
		(11 "B.Adhes" user "B.Adhesive")
		(13 "F.Paste" user "Package Geometry/Pastemask Top")
		(15 "B.Paste" user "Package Geometry/Pastemask Bottom")
		(5 "F.SilkS" user "Ref Des/Silkscreen Top")
		(7 "B.SilkS" user "Ref Des/Silkscreen Bottom")
		(1 "F.Mask" user "Board Geometry/Soldermask Top")
		(3 "B.Mask" user "Board Geometry/Soldermask Bottom")
		(17 "Dwgs.User" user "User.Drawings")
		(19 "Cmts.User" user "User.Comments")
		(21 "Eco1.User" user "User.Eco1")
		(23 "Eco2.User" user "User.Eco2")
		(25 "Edge.Cuts" user "Board Geometry/Outline")
		(27 "Margin" user)
		(31 "F.CrtYd" user "Package Geometry/Place Bound Top")
		(29 "B.CrtYd" user "Package Geometry/Place Bound Bottom")
		(35 "F.Fab" user "Ref Des/Assembly Top")
		(33 "B.Fab" user "Ref Des/Assembly Bottom")
	)
	(footprint ""
		(layer "F.Cu")
		(at 47.90948 -258.091686)
		(property "Reference" "J20"
			(at -2.74066 -81.678272 0)
			(unlocked yes)
			(layer "F.SilkS")
			(effects
				(font
					(size 0.7874 0.5842)
					(thickness 0.1524)
				)
				(justify left)
			)
		)
		(property "Value" ""
			(at 0 0 0)
			(layer "F.Fab")
			(effects
				(font
					(size 1.27 1.27)
				)
			)
		)
		(duplicate_pad_numbers_are_jumpers no)
		(pad "275" smd rect
			(at 2.050034 52.274978 270)
			(size 0.519938 1.4986)
			(layers "F.Cu" "F.Mask" "F.Paste")
			(net "GND")
		)
		(pad "276" smd rect
			(at 2.050034 53.125116 270)
			(size 0.519938 1.4986)
			(layers "F.Cu" "F.Mask" "F.Paste")
			(net "M_B_CPU1_SB_DQ<23>")
		)
		(pad "277" smd rect
			(at 2.050034 53.975 270)
			(size 0.519938 1.4986)
			(layers "F.Cu" "F.Mask" "F.Paste")
			(net "GND")
		)
		(pad "278" smd rect
			(at 2.050034 54.824884 270)
			(size 0.519938 1.4986)
			(layers "F.Cu" "F.Mask" "F.Paste")
			(net "M_B_CPU1_SB_DQ<26>")
		)
		(pad "279" smd rect
			(at 2.050034 55.675022 270)
			(size 0.519938 1.4986)
			(layers "F.Cu" "F.Mask" "F.Paste")
			(net "GND")
		)
		(pad "280" smd rect
			(at 2.050034 56.524906 270)
			(size 0.519938 1.4986)
			(layers "F.Cu" "F.Mask" "F.Paste")
			(net "M_B_CPU1_SB_DQ<27>")
		)
		(pad "281" smd rect
			(at 2.050034 57.375044 270)
			(size 0.519938 1.4986)
			(layers "F.Cu" "F.Mask" "F.Paste")
			(net "GND")
		)
		(pad "282" smd rect
			(at 2.050034 58.224928 270)
			(size 0.519938 1.4986)
			(layers "F.Cu" "F.Mask" "F.Paste")
			(net "M_B_CPU1_SB_DQS_DN<8>")
		)
		(pad "283" smd rect
			(at 2.050034 59.075066 270)
			(size 0.519938 1.4986)
			(layers "F.Cu" "F.Mask" "F.Paste")
			(net "M_B_CPU1_SB_DQS_DP<8>")
		)
		(pad "284" smd rect
			(at 2.050034 59.92495 270)
			(size 0.519938 1.4986)
			(layers "F.Cu" "F.Mask" "F.Paste")
			(net "GND")
		)
		(pad "285" smd rect
			(at 2.050034 60.775088 270)
			(size 0.519938 1.4986)
			(layers "F.Cu" "F.Mask" "F.Paste")
			(net "M_B_CPU1_SB_DQ<30>")
		)
		(pad "286" smd rect
			(at 2.050034 61.624972 270)
			(size 0.519938 1.4986)
			(layers "F.Cu" "F.Mask" "F.Paste")
			(net "GND")
		)
		(pad "287" smd rect
			(at 2.050034 62.47511 270)
			(size 0.519938 1.4986)
			(layers "F.Cu" "F.Mask" "F.Paste")
			(net "M_B_CPU1_SB_DQ<31>")
		)
		(pad "288" smd rect
			(at 2.050034 63.324994 270)
			(size 0.519938 1.4986)
			(layers "F.Cu" "F.Mask" "F.Paste")
			(net "GND")
		)
		(pad "G1" thru_hole oval
			(at 0 -68.97497)
			(size 2.8194 1.5748)
			(drill oval 2.4384 1.1938)
			(layers "*.Cu" "*.Mask")
			(remove_unused_layers no)
			(net "GND")
			(clearance 0.127)
			(thermal_gap 0.127)
		)
		(pad "G2" thru_hole oval
			(at 0 3.875024)
			(size 2.8194 1.5748)
			(drill oval 2.4384 1.1938)
			(layers "*.Cu" "*.Mask")
			(remove_unused_layers no)
			(net "GND")
			(clearance 0.127)
			(thermal_gap 0.127)
		)
		(pad "G3" thru_hole oval
			(at 0 68.97497)
			(size 2.8194 1.5748)
			(drill oval 2.4384 1.1938)
			(layers "*.Cu" "*.Mask")
			(remove_unused_layers no)
			(net "GND")
			(clearance 0.127)
			(thermal_gap 0.127)
		)
	)
)
